(kicad_pcb
	(version 20260206)
	(generator "pcbnew")
	(generator_version "10.0")
	(general
		(thickness 1.6)
		(legacy_teardrops no)
	)
	(paper "A4")
	(title_block
		(title "03242023_DA0F0TMBIJ0_F0T_Motherboard_J_brd_V01_OCP.brd")
		(comment 1 "Grand Teton / footprints 2505-2509 of 6105")
	)
	(layers
		(0 "F.Cu" signal "TOP")
		(4 "In1.Cu" signal "GND")
		(6 "In2.Cu" signal "IN1")
		(8 "In3.Cu" signal "GND1")
		(10 "In4.Cu" signal "IN2")
		(12 "In5.Cu" signal "GND2")
		(14 "In6.Cu" signal "IN3")
		(16 "In7.Cu" signal "GND3")
		(18 "In8.Cu" signal "VCC")
		(20 "In9.Cu" signal "VCC1")
		(22 "In10.Cu" signal "GND4")
		(24 "In11.Cu" signal "IN4")
		(26 "In12.Cu" signal "GND5")
		(28 "In13.Cu" signal "IN5")
		(30 "In14.Cu" signal "GND6")
		(32 "In15.Cu" signal "IN6")
		(34 "In16.Cu" signal "GND7")
		(2 "B.Cu" signal "BOTTOM")
		(9 "F.Adhes" user "F.Adhesive")
		(11 "B.Adhes" user "B.Adhesive")
		(13 "F.Paste" user "Package Geometry/Pastemask Top")
		(15 "B.Paste" user "Package Geometry/Pastemask Bottom")
		(5 "F.SilkS" user "Ref Des/Silkscreen Top")
		(7 "B.SilkS" user "Ref Des/Silkscreen Bottom")
		(1 "F.Mask" user "Board Geometry/Soldermask Top")
		(3 "B.Mask" user "Board Geometry/Soldermask Bottom")
		(17 "Dwgs.User" user "User.Drawings")
		(19 "Cmts.User" user "User.Comments")
		(21 "Eco1.User" user "User.Eco1")
		(23 "Eco2.User" user "User.Eco2")
		(25 "Edge.Cuts" user "Board Geometry/Outline")
		(27 "Margin" user)
		(31 "F.CrtYd" user "Package Geometry/Place Bound Top")
		(29 "B.CrtYd" user "Package Geometry/Place Bound Bottom")
		(35 "F.Fab" user "Ref Des/Assembly Top")
		(33 "B.Fab" user "Ref Des/Assembly Bottom")
	)
	(footprint ""
		(layer "F.Cu")
		(at 235.404406 -250.630436 180)
		(property "Reference" "U247"
			(at -2.7432 -3.012948 180)
			(unlocked yes)
			(layer "F.SilkS")
			(effects
				(font
					(size 0.7874 0.5842)
					(thickness 0.1524)
				)
				(justify left)
			)
		)
		(property "Value" ""
			(at 0 0 180)
			(layer "F.Fab")
			(effects
				(font
					(size 1.27 1.27)
				)
			)
		)
		(duplicate_pad_numbers_are_jumpers no)
		(fp_line
			(start 2.050034 2.050034)
			(end 2.050034 1.516634)
			(stroke
				(width 0.1524)
				(type default)
			)
			(layer "F.SilkS")
		)
		(fp_line
			(start 2.050034 -1.516634)
			(end 2.050034 -2.050034)
			(stroke
				(width 0.1524)
				(type default)
			)
			(layer "F.SilkS")
		)
		(fp_line
			(start 2.050034 -2.050034)
			(end 1.516634 -2.050034)
			(stroke
				(width 0.1524)
				(type default)
			)
			(layer "F.SilkS")
		)
		(fp_line
			(start 1.516634 2.050034)
			(end 2.050034 2.050034)
			(stroke
				(width 0.1524)
				(type default)
			)
			(layer "F.SilkS")
		)
		(fp_line
			(start -1.516634 -2.050034)
			(end -2.050034 -2.050034)
			(stroke
				(width 0.1524)
				(type default)
			)
			(layer "F.SilkS")
		)
		(fp_line
			(start -2.050034 2.050034)
			(end -1.516634 2.050034)
			(stroke
				(width 0.1524)
				(type default)
			)
			(layer "F.SilkS")
		)
		(fp_line
			(start -2.050034 1.516634)
			(end -2.050034 2.050034)
			(stroke
				(width 0.1524)
				(type default)
			)
			(layer "F.SilkS")
		)
		(fp_line
			(start -2.050034 -2.050034)
			(end -2.050034 -1.516634)
			(stroke
				(width 0.1524)
				(type default)
			)
			(layer "F.SilkS")
		)
		(fp_poly
			(pts
				(xy -2.634234 -1.542034) (xy -2.050034 -1.542034) (xy -2.050034 -2.126234) (xy -2.634234 -2.126234)
			)
			(stroke
				(width 0)
				(type default)
			)
			(fill yes)
			(layer "F.SilkS")
		)
		(fp_line
			(start 2.050034 2.050034)
			(end 2.050034 -2.050034)
			(stroke
				(width 0.1)
				(type default)
			)
			(layer "F.Fab")
		)
		(fp_line
			(start 2.050034 -2.050034)
			(end -2.050034 -2.050034)
			(stroke
				(width 0.1)
				(type default)
			)
			(layer "F.Fab")
		)
		(fp_line
			(start -2.050034 2.050034)
			(end 2.050034 2.050034)
			(stroke
				(width 0.1)
				(type default)
			)
			(layer "F.Fab")
		)
		(fp_line
			(start -2.050034 -2.050034)
			(end -2.050034 2.050034)
			(stroke
				(width 0.1)
				(type default)
			)
			(layer "F.Fab")
		)
		(fp_poly
			(pts
				(xy -2.634234 -1.542034) (xy -2.050034 -1.542034) (xy -2.050034 -2.126234) (xy -2.634234 -2.126234)
			)
			(stroke
				(width 0)
				(type default)
			)
			(fill yes)
			(layer "F.Fab")
		)
		(pad "1" smd rect
			(at -1.875028 -1.249934 90)
			(size 0.254 0.5588)
			(layers "F.Cu" "F.Mask" "F.Paste")
			(net "CLK_GEN2_XTAL_IN")
		)
		(pad "2" smd rect
			(at -1.875028 -0.750062 90)
			(size 0.254 0.5588)
			(layers "F.Cu" "F.Mask" "F.Paste")
			(net "CLK_GEN2_XTAL_OUT")
		)
		(pad "3" smd rect
			(at -1.875028 -0.249936 90)
			(size 0.254 0.5588)
			(layers "F.Cu" "F.Mask" "F.Paste")
			(net "VFG3P3_CLK_GEN")
		)
		(pad "4" smd rect
			(at -1.875028 0.249936 90)
			(size 0.254 0.5588)
			(layers "F.Cu" "F.Mask" "F.Paste")
			(net "CLK_GEN2_SMB_SADR")
		)
		(pad "5" smd rect
			(at -1.875028 0.750062 90)
			(size 0.254 0.5588)
			(layers "F.Cu" "F.Mask" "F.Paste")
			(net "GND")
		)
		(pad "6" smd rect
			(at -1.875028 1.249934 90)
			(size 0.254 0.5588)
			(layers "F.Cu" "F.Mask" "F.Paste")
			(net "GND")
		)
		(pad "7" smd rect
			(at -1.249934 1.875028 180)
			(size 0.254 0.5588)
			(layers "F.Cu" "F.Mask" "F.Paste")
			(net "VFG3P3_CLK_GEN")
		)
		(pad "8" smd rect
			(at -0.750062 1.875028 180)
			(size 0.254 0.5588)
			(layers "F.Cu" "F.Mask" "F.Paste")
			(net "SMB_HOST_CLK_GEN2_3V3AUX_SCL")
		)
		(pad "9" smd rect
			(at -0.249936 1.875028 180)
			(size 0.254 0.5588)
			(layers "F.Cu" "F.Mask" "F.Paste")
			(net "SMB_HOST_CLK_GEN2_3V3AUX_SDA")
		)
		(pad "10" smd rect
			(at 0.249936 1.875028 180)
			(size 0.254 0.5588)
			(layers "F.Cu" "F.Mask" "F.Paste")
			(net "GND")
		)
		(pad "11" smd rect
			(at 0.750062 1.875028 180)
			(size 0.254 0.5588)
			(layers "F.Cu" "F.Mask" "F.Paste")
			(net "VFG3P3_CLK_GEN")
		)
		(pad "12" smd rect
			(at 1.249934 1.875028 180)
			(size 0.254 0.5588)
			(layers "F.Cu" "F.Mask" "F.Paste")
			(net "CLK_GEN2_BMC_RC_OE_R3_N")
		)
		(pad "13" smd rect
			(at 1.875028 1.249934 90)
			(size 0.254 0.5588)
			(layers "F.Cu" "F.Mask" "F.Paste")
			(net "CLK_100M_BMC_RC_DP_R")
		)
		(pad "14" smd rect
			(at 1.875028 0.750062 90)
			(size 0.254 0.5588)
			(layers "F.Cu" "F.Mask" "F.Paste")
			(net "CLK_100M_BMC_RC_DN_R")
		)
		(pad "15" smd rect
			(at 1.875028 0.249936 90)
			(size 0.254 0.5588)
			(layers "F.Cu" "F.Mask" "F.Paste")
			(net "GND")
		)
		(pad "16" smd rect
			(at 1.875028 -0.249936 90)
			(size 0.254 0.5588)
			(layers "F.Cu" "F.Mask" "F.Paste")
			(net "VFG_3P3A_CLK_GEN")
		)
		(pad "17" smd rect
			(at 1.875028 -0.750062 90)
			(size 0.254 0.5588)
			(layers "F.Cu" "F.Mask" "F.Paste")
			(net "CLK_100M_GPU_FPGA_DP_R")
		)
		(pad "18" smd rect
			(at 1.875028 -1.249934 90)
			(size 0.254 0.5588)
			(layers "F.Cu" "F.Mask" "F.Paste")
			(net "CLK_100M_GPU_FPGA_DN_R")
		)
		(pad "19" smd rect
			(at 1.249934 -1.875028 180)
			(size 0.254 0.5588)
			(layers "F.Cu" "F.Mask" "F.Paste")
			(net "CLK_GEN2_GPU_OE_N")
		)
		(pad "20" smd rect
			(at 0.750062 -1.875028 180)
			(size 0.254 0.5588)
			(layers "F.Cu" "F.Mask" "F.Paste")
			(net "VFG3P3_CLK_GEN")
		)
		(pad "21" smd rect
			(at 0.249936 -1.875028 180)
			(size 0.254 0.5588)
			(layers "F.Cu" "F.Mask" "F.Paste")
			(net "GND")
		)
		(pad "22" smd rect
			(at -0.249936 -1.875028 180)
			(size 0.254 0.5588)
			(layers "F.Cu" "F.Mask" "F.Paste")
			(net "P3V3_PWRGD_CLKGEN")
		)
		(pad "23" smd rect
			(at -0.750062 -1.875028 180)
			(size 0.254 0.5588)
			(layers "F.Cu" "F.Mask" "F.Paste")
			(net "FG_SS_EN")
		)
		(pad "24" smd rect
			(at -1.249934 -1.875028 180)
			(size 0.254 0.5588)
			(layers "F.Cu" "F.Mask" "F.Paste")
			(net "GND")
		)
		(pad "25" smd circle
			(at 0 0 180)
			(size 0 0)
			(layers "F.Cu" "F.Mask" "F.Paste")
			(net "GND")
		)
	)
	(footprint ""
		(layer "F.Cu")
		(at 176.58588 -130.266948 -90)
		(property "Reference" "R1447"
			(at 0 0 270)
			(layer "F.SilkS")
			(hide yes)
			(effects
				(font
					(size 1.27 1.27)
				)
			)
		)
		(property "Value" ""
			(at 0 0 270)
			(layer "F.Fab")
			(effects
				(font
					(size 1.27 1.27)
				)
			)
		)
		(duplicate_pad_numbers_are_jumpers no)
		(fp_line
			(start -0.7874 0.4064)
			(end -0.7874 -0.4064)
			(stroke
				(width 0.1524)
				(type default)
			)
			(layer "F.SilkS")
		)
		(fp_line
			(start 0.7874 0.4064)
			(end -0.7874 0.4064)
			(stroke
				(width 0.1524)
				(type default)
			)
			(layer "F.SilkS")
		)
		(fp_line
			(start -0.7874 -0.4064)
			(end 0.7874 -0.4064)
			(stroke
				(width 0.1524)
				(type default)
			)
			(layer "F.SilkS")
		)
		(fp_line
			(start 0.7874 -0.4064)
			(end 0.7874 0.4064)
			(stroke
				(width 0.1524)
				(type default)
			)
			(layer "F.SilkS")
		)
		(fp_line
			(start -0.67945 0.3048)
			(end -0.67945 -0.305054)
			(stroke
				(width 0.1)
				(type default)
			)
			(layer "F.Fab")
		)
		(fp_line
			(start -0.12065 0.3048)
			(end -0.67945 0.3048)
			(stroke
				(width 0.1)
				(type default)
			)
			(layer "F.Fab")
		)
		(fp_line
			(start 0.120396 0.3048)
			(end 0.120396 0.2794)
			(stroke
				(width 0.1)
				(type default)
			)
			(layer "F.Fab")
		)
		(fp_line
			(start 0.67945 0.3048)
			(end 0.120396 0.3048)
			(stroke
				(width 0.1)
				(type default)
			)
			(layer "F.Fab")
		)
		(fp_line
			(start -0.12065 0.2794)
			(end -0.12065 0.3048)
			(stroke
				(width 0.1)
				(type default)
			)
			(layer "F.Fab")
		)
		(fp_line
			(start 0.120396 0.2794)
			(end -0.12065 0.2794)
			(stroke
				(width 0.1)
				(type default)
			)
			(layer "F.Fab")
		)
		(fp_line
			(start -0.12065 -0.2794)
			(end 0.12065 -0.2794)
			(stroke
				(width 0.1)
				(type default)
			)
			(layer "F.Fab")
		)
		(fp_line
			(start 0.12065 -0.2794)
			(end 0.12065 -0.3048)
			(stroke
				(width 0.1)
				(type default)
			)
			(layer "F.Fab")
		)
		(fp_line
			(start 0.12065 -0.3048)
			(end 0.67945 -0.3048)
			(stroke
				(width 0.1)
				(type default)
			)
			(layer "F.Fab")
		)
		(fp_line
			(start 0.67945 -0.3048)
			(end 0.67945 0.3048)
			(stroke
				(width 0.1)
				(type default)
			)
			(layer "F.Fab")
		)
		(fp_line
			(start -0.67945 -0.305054)
			(end -0.12065 -0.305054)
			(stroke
				(width 0.1)
				(type default)
			)
			(layer "F.Fab")
		)
		(fp_line
			(start -0.12065 -0.305054)
			(end -0.12065 -0.2794)
			(stroke
				(width 0.1)
				(type default)
			)
			(layer "F.Fab")
		)
		(pad "1" smd circle
			(at -0.40005 0 270)
			(size 0 0)
			(layers "F.Cu" "F.Mask" "F.Paste")
			(net "FM_CPU0_SKTOCC_LVT3_N")
		)
		(pad "2" smd circle
			(at 0.40005 0 270)
			(size 0 0)
			(layers "F.Cu" "F.Mask" "F.Paste")
			(net "FM_CPU0_SKTOCC_LVT3_PLD_N")
		)
	)
	(footprint ""
		(layer "F.Cu")
		(at 118.849902 -409.113228 180)
		(property "Reference" "R2920"
			(at 0 0 180)
			(layer "F.SilkS")
			(hide yes)
			(effects
				(font
					(size 1.27 1.27)
				)
			)
		)
		(property "Value" ""
			(at 0 0 180)
			(layer "F.Fab")
			(effects
				(font
					(size 1.27 1.27)
				)
			)
		)
		(duplicate_pad_numbers_are_jumpers no)
		(fp_line
			(start 0.7874 0.4064)
			(end -0.7874 0.4064)
			(stroke
				(width 0.1524)
				(type default)
			)
			(layer "F.SilkS")
		)
		(fp_line
			(start 0.7874 -0.4064)
			(end 0.7874 0.4064)
			(stroke
				(width 0.1524)
				(type default)
			)
			(layer "F.SilkS")
		)
		(fp_line
			(start -0.7874 0.4064)
			(end -0.7874 -0.4064)
			(stroke
				(width 0.1524)
				(type default)
			)
			(layer "F.SilkS")
		)
		(fp_line
			(start -0.7874 -0.4064)
			(end 0.7874 -0.4064)
			(stroke
				(width 0.1524)
				(type default)
			)
			(layer "F.SilkS")
		)
		(fp_line
			(start 0.67945 0.3048)
			(end 0.120396 0.3048)
			(stroke
				(width 0.1)
				(type default)
			)
			(layer "F.Fab")
		)
		(fp_line
			(start 0.67945 -0.3048)
			(end 0.67945 0.3048)
			(stroke
				(width 0.1)
				(type default)
			)
			(layer "F.Fab")
		)
		(fp_line
			(start 0.12065 -0.2794)
			(end 0.12065 -0.3048)
			(stroke
				(width 0.1)
				(type default)
			)
			(layer "F.Fab")
		)
		(fp_line
			(start 0.12065 -0.3048)
			(end 0.67945 -0.3048)
			(stroke
				(width 0.1)
				(type default)
			)
			(layer "F.Fab")
		)
		(fp_line
			(start 0.120396 0.3048)
			(end 0.120396 0.2794)
			(stroke
				(width 0.1)
				(type default)
			)
			(layer "F.Fab")
		)
		(fp_line
			(start 0.120396 0.2794)
			(end -0.12065 0.2794)
			(stroke
				(width 0.1)
				(type default)
			)
			(layer "F.Fab")
		)
		(fp_line
			(start -0.12065 0.3048)
			(end -0.67945 0.3048)
			(stroke
				(width 0.1)
				(type default)
			)
			(layer "F.Fab")
		)
		(fp_line
			(start -0.12065 0.2794)
			(end -0.12065 0.3048)
			(stroke
				(width 0.1)
				(type default)
			)
			(layer "F.Fab")
		)
		(fp_line
			(start -0.12065 -0.2794)
			(end 0.12065 -0.2794)
			(stroke
				(width 0.1)
				(type default)
			)
			(layer "F.Fab")
		)
		(fp_line
			(start -0.12065 -0.305054)
			(end -0.12065 -0.2794)
			(stroke
				(width 0.1)
				(type default)
			)
			(layer "F.Fab")
		)
		(fp_line
			(start -0.67945 0.3048)
			(end -0.67945 -0.305054)
			(stroke
				(width 0.1)
				(type default)
			)
			(layer "F.Fab")
		)
		(fp_line
			(start -0.67945 -0.305054)
			(end -0.12065 -0.305054)
			(stroke
				(width 0.1)
				(type default)
			)
			(layer "F.Fab")
		)
		(pad "1" smd circle
			(at -0.40005 0 180)
			(size 0 0)
			(layers "F.Cu" "F.Mask" "F.Paste")
			(net "P3V3_AUX")
		)
		(pad "2" smd circle
			(at 0.40005 0 180)
			(size 0 0)
			(layers "F.Cu" "F.Mask" "F.Paste")
			(net "BIC_MONITER_ISO")
		)
	)
	(footprint ""
		(layer "F.Cu")
		(at 52.50688 -434.304948 180)
		(property "Reference" "R3110"
			(at 0 0 180)
			(layer "F.SilkS")
			(hide yes)
			(effects
				(font
					(size 1.27 1.27)
				)
			)
		)
		(property "Value" ""
			(at 0 0 180)
			(layer "F.Fab")
			(effects
				(font
					(size 1.27 1.27)
				)
			)
		)
		(duplicate_pad_numbers_are_jumpers no)
		(fp_line
			(start 0.7874 0.4064)
			(end -0.7874 0.4064)
			(stroke
				(width 0.1524)
				(type default)
			)
			(layer "F.SilkS")
		)
		(fp_line
			(start 0.7874 -0.4064)
			(end 0.7874 0.4064)
			(stroke
				(width 0.1524)
				(type default)
			)
			(layer "F.SilkS")
		)
		(fp_line
			(start -0.7874 0.4064)
			(end -0.7874 -0.4064)
			(stroke
				(width 0.1524)
				(type default)
			)
			(layer "F.SilkS")
		)
		(fp_line
			(start -0.7874 -0.4064)
			(end 0.7874 -0.4064)
			(stroke
				(width 0.1524)
				(type default)
			)
			(layer "F.SilkS")
		)
		(fp_line
			(start 0.67945 0.3048)
			(end 0.120396 0.3048)
			(stroke
				(width 0.1)
				(type default)
			)
			(layer "F.Fab")
		)
		(fp_line
			(start 0.67945 -0.3048)
			(end 0.67945 0.3048)
			(stroke
				(width 0.1)
				(type default)
			)
			(layer "F.Fab")
		)
		(fp_line
			(start 0.12065 -0.2794)
			(end 0.12065 -0.3048)
			(stroke
				(width 0.1)
				(type default)
			)
			(layer "F.Fab")
		)
		(fp_line
			(start 0.12065 -0.3048)
			(end 0.67945 -0.3048)
			(stroke
				(width 0.1)
				(type default)
			)
			(layer "F.Fab")
		)
		(fp_line
			(start 0.120396 0.3048)
			(end 0.120396 0.2794)
			(stroke
				(width 0.1)
				(type default)
			)
			(layer "F.Fab")
		)
		(fp_line
			(start 0.120396 0.2794)
			(end -0.12065 0.2794)
			(stroke
				(width 0.1)
				(type default)
			)
			(layer "F.Fab")
		)
		(fp_line
			(start -0.12065 0.3048)
			(end -0.67945 0.3048)
			(stroke
				(width 0.1)
				(type default)
			)
			(layer "F.Fab")
		)
		(fp_line
			(start -0.12065 0.2794)
			(end -0.12065 0.3048)
			(stroke
				(width 0.1)
				(type default)
			)
			(layer "F.Fab")
		)
		(fp_line
			(start -0.12065 -0.2794)
			(end 0.12065 -0.2794)
			(stroke
				(width 0.1)
				(type default)
			)
			(layer "F.Fab")
		)
		(fp_line
			(start -0.12065 -0.305054)
			(end -0.12065 -0.2794)
			(stroke
				(width 0.1)
				(type default)
			)
			(layer "F.Fab")
		)
		(fp_line
			(start -0.67945 0.3048)
			(end -0.67945 -0.305054)
			(stroke
				(width 0.1)
				(type default)
			)
			(layer "F.Fab")
		)
		(fp_line
			(start -0.67945 -0.305054)
			(end -0.12065 -0.305054)
			(stroke
				(width 0.1)
				(type default)
			)
			(layer "F.Fab")
		)
		(pad "1" smd circle
			(at -0.40005 0 180)
			(size 0 0)
			(layers "F.Cu" "F.Mask" "F.Paste")
			(net "SMB_1_BMC_GPU_SDA")
		)
		(pad "2" smd circle
			(at 0.40005 0 180)
			(size 0 0)
			(layers "F.Cu" "F.Mask" "F.Paste")
			(net "SMB_1_BMC_GPU_R_SDA")
		)
	)
	(footprint ""
		(layer "F.Cu")
		(at 119.508016 -258.72694 90)
		(property "Reference" "C233"
			(at 0 0 90)
			(layer "F.SilkS")
			(hide yes)
			(effects
				(font
					(size 1.27 1.27)
				)
			)
		)
		(property "Value" ""
			(at 0 0 90)
			(layer "F.Fab")
			(effects
				(font
					(size 1.27 1.27)
				)
			)
		)
		(duplicate_pad_numbers_are_jumpers no)
		(fp_line
			(start 0.7874 -0.4064)
			(end 0.7874 0.4064)
			(stroke
				(width 0.1524)
				(type default)
			)
			(layer "F.SilkS")
		)
		(fp_line
			(start -0.7874 -0.4064)
			(end 0.7874 -0.4064)
			(stroke
				(width 0.1524)
				(type default)
			)
			(layer "F.SilkS")
		)
		(fp_line
			(start 0.7874 0.4064)
			(end -0.7874 0.4064)
			(stroke
				(width 0.1524)
				(type default)
			)
			(layer "F.SilkS")
		)
		(fp_line
			(start -0.7874 0.4064)
			(end -0.7874 -0.4064)
			(stroke
				(width 0.1524)
				(type default)
			)
			(layer "F.SilkS")
		)
		(fp_line
			(start -0.12065 -0.305054)
			(end -0.12065 -0.2794)
			(stroke
				(width 0.1)
				(type default)
			)
			(layer "F.Fab")
		)
		(fp_line
			(start -0.67945 -0.305054)
			(end -0.12065 -0.305054)
			(stroke
				(width 0.1)
				(type default)
			)
			(layer "F.Fab")
		)
		(fp_line
			(start 0.67945 -0.3048)
			(end 0.67945 0.3048)
			(stroke
				(width 0.1)
				(type default)
			)
			(layer "F.Fab")
		)
		(fp_line
			(start 0.12065 -0.3048)
			(end 0.67945 -0.3048)
			(stroke
				(width 0.1)
				(type default)
			)
			(layer "F.Fab")
		)
		(fp_line
			(start 0.12065 -0.2794)
			(end 0.12065 -0.3048)
			(stroke
				(width 0.1)
				(type default)
			)
			(layer "F.Fab")
		)
		(fp_line
			(start -0.12065 -0.2794)
			(end 0.12065 -0.2794)
			(stroke
				(width 0.1)
				(type default)
			)
			(layer "F.Fab")
		)
		(fp_line
			(start 0.120396 0.2794)
			(end -0.12065 0.2794)
			(stroke
				(width 0.1)
				(type default)
			)
			(layer "F.Fab")
		)
		(fp_line
			(start -0.12065 0.2794)
			(end -0.12065 0.3048)
			(stroke
				(width 0.1)
				(type default)
			)
			(layer "F.Fab")
		)
		(fp_line
			(start 0.67945 0.3048)
			(end 0.120396 0.3048)
			(stroke
				(width 0.1)
				(type default)
			)
			(layer "F.Fab")
		)
		(fp_line
			(start 0.120396 0.3048)
			(end 0.120396 0.2794)
			(stroke
				(width 0.1)
				(type default)
			)
			(layer "F.Fab")
		)
		(fp_line
			(start -0.12065 0.3048)
			(end -0.67945 0.3048)
			(stroke
				(width 0.1)
				(type default)
			)
			(layer "F.Fab")
		)
		(fp_line
			(start -0.67945 0.3048)
			(end -0.67945 -0.305054)
			(stroke
				(width 0.1)
				(type default)
			)
			(layer "F.Fab")
		)
		(pad "1" smd circle
			(at -0.40005 0 90)
			(size 0 0)
			(layers "F.Cu" "F.Mask" "F.Paste")
			(net "PVCCIN_CPU1")
		)
		(pad "2" smd circle
			(at 0.40005 0 90)
			(size 0 0)
			(layers "F.Cu" "F.Mask" "F.Paste")
			(net "GND")
		)
	)
)
